(kicad_pcb
	(version 20260206)
	(generator "pcbnew")
	(generator_version "10.0")
	(general
		(thickness 1.6)
		(legacy_teardrops no)
	)
	(paper "A4")
	(title_block
		(title "01162023_DA0F0TEBIF0_F0T_Expander_BD_F_brd_V02_OCP.brd")
		(comment 1 "Grand Teton / footprints 9417-9424 of 9728")
	)
	(layers
		(0 "F.Cu" signal "TOP")
		(4 "In1.Cu" signal "GND")
		(6 "In2.Cu" signal "VCC")
		(8 "In3.Cu" signal "VCC1")
		(10 "In4.Cu" signal "GND1")
		(12 "In5.Cu" signal "IN1")
		(14 "In6.Cu" signal "GND2")
		(16 "In7.Cu" signal "IN2")
		(18 "In8.Cu" signal "GND3")
		(20 "In9.Cu" signal "IN3")
		(22 "In10.Cu" signal "GND4")
		(24 "In11.Cu" signal "IN4")
		(26 "In12.Cu" signal "GND5")
		(28 "In13.Cu" signal "IN5")
		(30 "In14.Cu" signal "GND6")
		(32 "In15.Cu" signal "IN6")
		(34 "In16.Cu" signal "GND7")
		(2 "B.Cu" signal "BOTTOM")
		(9 "F.Adhes" user "F.Adhesive")
		(11 "B.Adhes" user "B.Adhesive")
		(13 "F.Paste" user "Package Geometry/Pastemask Top")
		(15 "B.Paste" user "Package Geometry/Pastemask Bottom")
		(5 "F.SilkS" user "Ref Des/Silkscreen Top")
		(7 "B.SilkS" user "Ref Des/Silkscreen Bottom")
		(1 "F.Mask" user "Board Geometry/Soldermask Top")
		(3 "B.Mask" user "Board Geometry/Soldermask Bottom")
		(17 "Dwgs.User" user "User.Drawings")
		(19 "Cmts.User" user "User.Comments")
		(21 "Eco1.User" user "User.Eco1")
		(23 "Eco2.User" user "User.Eco2")
		(25 "Edge.Cuts" user "Board Geometry/Outline")
		(27 "Margin" user)
		(31 "F.CrtYd" user "Package Geometry/Place Bound Top")
		(29 "B.CrtYd" user "Package Geometry/Place Bound Bottom")
		(35 "F.Fab" user "Ref Des/Assembly Top")
		(33 "B.Fab" user "Ref Des/Assembly Bottom")
	)
	(footprint ""
		(layer "B.Cu")
		(at 348.477586 -254.55372 180)
		(property "Reference" "PR116"
			(at 0 0 0)
			(layer "B.SilkS")
			(hide yes)
			(effects
				(font
					(size 1.27 1.27)
				)
				(justify mirror)
			)
		)
		(property "Value" ""
			(at 0 0 0)
			(layer "B.Fab")
			(effects
				(font
					(size 1.27 1.27)
				)
				(justify mirror)
			)
		)
		(duplicate_pad_numbers_are_jumpers no)
		(fp_line
			(start 0.7874 0.4064)
			(end 0.7874 -0.4064)
			(stroke
				(width 0.1524)
				(type default)
			)
			(layer "B.SilkS")
		)
		(fp_line
			(start 0.7874 -0.4064)
			(end -0.7874 -0.4064)
			(stroke
				(width 0.1524)
				(type default)
			)
			(layer "B.SilkS")
		)
		(fp_line
			(start -0.7874 0.4064)
			(end 0.7874 0.4064)
			(stroke
				(width 0.1524)
				(type default)
			)
			(layer "B.SilkS")
		)
		(fp_line
			(start -0.7874 -0.4064)
			(end -0.7874 0.4064)
			(stroke
				(width 0.1524)
				(type default)
			)
			(layer "B.SilkS")
		)
		(fp_line
			(start 0.67945 0.3048)
			(end 0.67945 -0.305054)
			(stroke
				(width 0.1)
				(type default)
			)
			(layer "B.Fab")
		)
		(fp_line
			(start 0.67945 -0.305054)
			(end 0.12065 -0.305054)
			(stroke
				(width 0.1)
				(type default)
			)
			(layer "B.Fab")
		)
		(fp_line
			(start 0.12065 0.3048)
			(end 0.67945 0.3048)
			(stroke
				(width 0.1)
				(type default)
			)
			(layer "B.Fab")
		)
		(fp_line
			(start 0.12065 0.2794)
			(end 0.12065 0.3048)
			(stroke
				(width 0.1)
				(type default)
			)
			(layer "B.Fab")
		)
		(fp_line
			(start 0.12065 -0.2794)
			(end -0.12065 -0.2794)
			(stroke
				(width 0.1)
				(type default)
			)
			(layer "B.Fab")
		)
		(fp_line
			(start 0.12065 -0.305054)
			(end 0.12065 -0.2794)
			(stroke
				(width 0.1)
				(type default)
			)
			(layer "B.Fab")
		)
		(fp_line
			(start -0.120396 0.3048)
			(end -0.120396 0.2794)
			(stroke
				(width 0.1)
				(type default)
			)
			(layer "B.Fab")
		)
		(fp_line
			(start -0.120396 0.2794)
			(end 0.12065 0.2794)
			(stroke
				(width 0.1)
				(type default)
			)
			(layer "B.Fab")
		)
		(fp_line
			(start -0.12065 -0.2794)
			(end -0.12065 -0.3048)
			(stroke
				(width 0.1)
				(type default)
			)
			(layer "B.Fab")
		)
		(fp_line
			(start -0.12065 -0.3048)
			(end -0.67945 -0.3048)
			(stroke
				(width 0.1)
				(type default)
			)
			(layer "B.Fab")
		)
		(fp_line
			(start -0.67945 0.3048)
			(end -0.120396 0.3048)
			(stroke
				(width 0.1)
				(type default)
			)
			(layer "B.Fab")
		)
		(fp_line
			(start -0.67945 -0.3048)
			(end -0.67945 0.3048)
			(stroke
				(width 0.1)
				(type default)
			)
			(layer "B.Fab")
		)
		(pad "1" smd circle
			(at 0.40005 0)
			(size 0 0)
			(layers "B.Cu" "B.Mask" "B.Paste")
			(net "P3V3_AUX")
		)
		(pad "2" smd circle
			(at -0.40005 0)
			(size 0 0)
			(layers "B.Cu" "B.Mask" "B.Paste")
			(net "P0V8_PEX2_VDD")
		)
	)
	(footprint ""
		(layer "B.Cu")
		(at 286.149796 -301.599854 -90)
		(property "Reference" "C1714"
			(at 0 0 90)
			(layer "B.SilkS")
			(hide yes)
			(effects
				(font
					(size 1.27 1.27)
				)
				(justify mirror)
			)
		)
		(property "Value" ""
			(at 0 0 90)
			(layer "B.Fab")
			(effects
				(font
					(size 1.27 1.27)
				)
				(justify mirror)
			)
		)
		(duplicate_pad_numbers_are_jumpers no)
		(fp_line
			(start -0.299974 0.150114)
			(end 0.299974 0.150114)
			(stroke
				(width 0.1)
				(type default)
			)
			(layer "B.Fab")
		)
		(fp_line
			(start 0.299974 0.150114)
			(end 0.299974 -0.150114)
			(stroke
				(width 0.1)
				(type default)
			)
			(layer "B.Fab")
		)
		(fp_line
			(start -0.299974 -0.150114)
			(end -0.299974 0.150114)
			(stroke
				(width 0.1)
				(type default)
			)
			(layer "B.Fab")
		)
		(fp_line
			(start 0.299974 -0.150114)
			(end -0.299974 -0.150114)
			(stroke
				(width 0.1)
				(type default)
			)
			(layer "B.Fab")
		)
		(pad "1" smd rect
			(at 0.2667 0 90)
			(size 0.3048 0.381)
			(layers "B.Cu" "B.Mask" "B.Paste")
			(net "P0V8_SERDES_VDDA_PEX2")
		)
		(pad "2" smd rect
			(at -0.2667 0 90)
			(size 0.3048 0.381)
			(layers "B.Cu" "B.Mask" "B.Paste")
			(net "GND")
		)
	)
	(footprint ""
		(layer "B.Cu")
		(at 346.65031 -256.226564 -90)
		(property "Reference" "PR146"
			(at 0 0 90)
			(layer "B.SilkS")
			(hide yes)
			(effects
				(font
					(size 1.27 1.27)
				)
				(justify mirror)
			)
		)
		(property "Value" ""
			(at 0 0 90)
			(layer "B.Fab")
			(effects
				(font
					(size 1.27 1.27)
				)
				(justify mirror)
			)
		)
		(duplicate_pad_numbers_are_jumpers no)
		(fp_line
			(start -0.7874 0.4064)
			(end 0.7874 0.4064)
			(stroke
				(width 0.1524)
				(type default)
			)
			(layer "B.SilkS")
		)
		(fp_line
			(start 0.7874 0.4064)
			(end 0.7874 -0.4064)
			(stroke
				(width 0.1524)
				(type default)
			)
			(layer "B.SilkS")
		)
		(fp_line
			(start -0.7874 -0.4064)
			(end -0.7874 0.4064)
			(stroke
				(width 0.1524)
				(type default)
			)
			(layer "B.SilkS")
		)
		(fp_line
			(start 0.7874 -0.4064)
			(end -0.7874 -0.4064)
			(stroke
				(width 0.1524)
				(type default)
			)
			(layer "B.SilkS")
		)
		(fp_line
			(start -0.67945 0.3048)
			(end -0.120396 0.3048)
			(stroke
				(width 0.1)
				(type default)
			)
			(layer "B.Fab")
		)
		(fp_line
			(start -0.120396 0.3048)
			(end -0.120396 0.2794)
			(stroke
				(width 0.1)
				(type default)
			)
			(layer "B.Fab")
		)
		(fp_line
			(start 0.12065 0.3048)
			(end 0.67945 0.3048)
			(stroke
				(width 0.1)
				(type default)
			)
			(layer "B.Fab")
		)
		(fp_line
			(start 0.67945 0.3048)
			(end 0.67945 -0.305054)
			(stroke
				(width 0.1)
				(type default)
			)
			(layer "B.Fab")
		)
		(fp_line
			(start -0.120396 0.2794)
			(end 0.12065 0.2794)
			(stroke
				(width 0.1)
				(type default)
			)
			(layer "B.Fab")
		)
		(fp_line
			(start 0.12065 0.2794)
			(end 0.12065 0.3048)
			(stroke
				(width 0.1)
				(type default)
			)
			(layer "B.Fab")
		)
		(fp_line
			(start -0.12065 -0.2794)
			(end -0.12065 -0.3048)
			(stroke
				(width 0.1)
				(type default)
			)
			(layer "B.Fab")
		)
		(fp_line
			(start 0.12065 -0.2794)
			(end -0.12065 -0.2794)
			(stroke
				(width 0.1)
				(type default)
			)
			(layer "B.Fab")
		)
		(fp_line
			(start -0.67945 -0.3048)
			(end -0.67945 0.3048)
			(stroke
				(width 0.1)
				(type default)
			)
			(layer "B.Fab")
		)
		(fp_line
			(start -0.12065 -0.3048)
			(end -0.67945 -0.3048)
			(stroke
				(width 0.1)
				(type default)
			)
			(layer "B.Fab")
		)
		(fp_line
			(start 0.12065 -0.305054)
			(end 0.12065 -0.2794)
			(stroke
				(width 0.1)
				(type default)
			)
			(layer "B.Fab")
		)
		(fp_line
			(start 0.67945 -0.305054)
			(end 0.12065 -0.305054)
			(stroke
				(width 0.1)
				(type default)
			)
			(layer "B.Fab")
		)
		(pad "1" smd circle
			(at 0.40005 0 90)
			(size 0 0)
			(layers "B.Cu" "B.Mask" "B.Paste")
			(net "P12V_AUX")
		)
		(pad "2" smd circle
			(at -0.40005 0 90)
			(size 0 0)
			(layers "B.Cu" "B.Mask" "B.Paste")
			(net "P0V8_PEX2_VINSEN")
		)
	)
	(footprint ""
		(layer "B.Cu")
		(at 281.755342 -156.0576)
		(property "Reference" "R232"
			(at 0 0 0)
			(layer "B.SilkS")
			(hide yes)
			(effects
				(font
					(size 1.27 1.27)
				)
				(justify mirror)
			)
		)
		(property "Value" ""
			(at 0 0 0)
			(layer "B.Fab")
			(effects
				(font
					(size 1.27 1.27)
				)
				(justify mirror)
			)
		)
		(duplicate_pad_numbers_are_jumpers no)
		(fp_line
			(start -0.7874 -0.4064)
			(end -0.7874 0.4064)
			(stroke
				(width 0.1524)
				(type default)
			)
			(layer "B.SilkS")
		)
		(fp_line
			(start -0.7874 0.4064)
			(end 0.7874 0.4064)
			(stroke
				(width 0.1524)
				(type default)
			)
			(layer "B.SilkS")
		)
		(fp_line
			(start 0.7874 -0.4064)
			(end -0.7874 -0.4064)
			(stroke
				(width 0.1524)
				(type default)
			)
			(layer "B.SilkS")
		)
		(fp_line
			(start 0.7874 0.4064)
			(end 0.7874 -0.4064)
			(stroke
				(width 0.1524)
				(type default)
			)
			(layer "B.SilkS")
		)
		(fp_line
			(start -0.67945 -0.3048)
			(end -0.67945 0.3048)
			(stroke
				(width 0.1)
				(type default)
			)
			(layer "B.Fab")
		)
		(fp_line
			(start -0.67945 0.3048)
			(end -0.120396 0.3048)
			(stroke
				(width 0.1)
				(type default)
			)
			(layer "B.Fab")
		)
		(fp_line
			(start -0.12065 -0.3048)
			(end -0.67945 -0.3048)
			(stroke
				(width 0.1)
				(type default)
			)
			(layer "B.Fab")
		)
		(fp_line
			(start -0.12065 -0.2794)
			(end -0.12065 -0.3048)
			(stroke
				(width 0.1)
				(type default)
			)
			(layer "B.Fab")
		)
		(fp_line
			(start -0.120396 0.2794)
			(end 0.12065 0.2794)
			(stroke
				(width 0.1)
				(type default)
			)
			(layer "B.Fab")
		)
		(fp_line
			(start -0.120396 0.3048)
			(end -0.120396 0.2794)
			(stroke
				(width 0.1)
				(type default)
			)
			(layer "B.Fab")
		)
		(fp_line
			(start 0.12065 -0.305054)
			(end 0.12065 -0.2794)
			(stroke
				(width 0.1)
				(type default)
			)
			(layer "B.Fab")
		)
		(fp_line
			(start 0.12065 -0.2794)
			(end -0.12065 -0.2794)
			(stroke
				(width 0.1)
				(type default)
			)
			(layer "B.Fab")
		)
		(fp_line
			(start 0.12065 0.2794)
			(end 0.12065 0.3048)
			(stroke
				(width 0.1)
				(type default)
			)
			(layer "B.Fab")
		)
		(fp_line
			(start 0.12065 0.3048)
			(end 0.67945 0.3048)
			(stroke
				(width 0.1)
				(type default)
			)
			(layer "B.Fab")
		)
		(fp_line
			(start 0.67945 -0.305054)
			(end 0.12065 -0.305054)
			(stroke
				(width 0.1)
				(type default)
			)
			(layer "B.Fab")
		)
		(fp_line
			(start 0.67945 0.3048)
			(end 0.67945 -0.305054)
			(stroke
				(width 0.1)
				(type default)
			)
			(layer "B.Fab")
		)
		(pad "1" smd circle
			(at 0.40005 0 180)
			(size 0 0)
			(layers "B.Cu" "B.Mask" "B.Paste")
			(net "NIC4_SLOT_ID1")
		)
		(pad "2" smd circle
			(at -0.40005 0 180)
			(size 0 0)
			(layers "B.Cu" "B.Mask" "B.Paste")
			(net "GND")
		)
	)
	(footprint ""
		(layer "B.Cu")
		(at 232.620312 -208.809082)
		(property "Reference" "R6152"
			(at 0 0 0)
			(layer "B.SilkS")
			(hide yes)
			(effects
				(font
					(size 1.27 1.27)
				)
				(justify mirror)
			)
		)
		(property "Value" ""
			(at 0 0 0)
			(layer "B.Fab")
			(effects
				(font
					(size 1.27 1.27)
				)
				(justify mirror)
			)
		)
		(duplicate_pad_numbers_are_jumpers no)
		(fp_line
			(start -0.7874 -0.4064)
			(end -0.7874 0.4064)
			(stroke
				(width 0.1524)
				(type default)
			)
			(layer "B.SilkS")
		)
		(fp_line
			(start -0.7874 0.4064)
			(end 0.7874 0.4064)
			(stroke
				(width 0.1524)
				(type default)
			)
			(layer "B.SilkS")
		)
		(fp_line
			(start 0.7874 -0.4064)
			(end -0.7874 -0.4064)
			(stroke
				(width 0.1524)
				(type default)
			)
			(layer "B.SilkS")
		)
		(fp_line
			(start 0.7874 0.4064)
			(end 0.7874 -0.4064)
			(stroke
				(width 0.1524)
				(type default)
			)
			(layer "B.SilkS")
		)
		(fp_line
			(start -0.67945 -0.3048)
			(end -0.67945 0.3048)
			(stroke
				(width 0.1)
				(type default)
			)
			(layer "B.Fab")
		)
		(fp_line
			(start -0.67945 0.3048)
			(end -0.120396 0.3048)
			(stroke
				(width 0.1)
				(type default)
			)
			(layer "B.Fab")
		)
		(fp_line
			(start -0.12065 -0.3048)
			(end -0.67945 -0.3048)
			(stroke
				(width 0.1)
				(type default)
			)
			(layer "B.Fab")
		)
		(fp_line
			(start -0.12065 -0.2794)
			(end -0.12065 -0.3048)
			(stroke
				(width 0.1)
				(type default)
			)
			(layer "B.Fab")
		)
		(fp_line
			(start -0.120396 0.2794)
			(end 0.12065 0.2794)
			(stroke
				(width 0.1)
				(type default)
			)
			(layer "B.Fab")
		)
		(fp_line
			(start -0.120396 0.3048)
			(end -0.120396 0.2794)
			(stroke
				(width 0.1)
				(type default)
			)
			(layer "B.Fab")
		)
		(fp_line
			(start 0.12065 -0.305054)
			(end 0.12065 -0.2794)
			(stroke
				(width 0.1)
				(type default)
			)
			(layer "B.Fab")
		)
		(fp_line
			(start 0.12065 -0.2794)
			(end -0.12065 -0.2794)
			(stroke
				(width 0.1)
				(type default)
			)
			(layer "B.Fab")
		)
		(fp_line
			(start 0.12065 0.2794)
			(end 0.12065 0.3048)
			(stroke
				(width 0.1)
				(type default)
			)
			(layer "B.Fab")
		)
		(fp_line
			(start 0.12065 0.3048)
			(end 0.67945 0.3048)
			(stroke
				(width 0.1)
				(type default)
			)
			(layer "B.Fab")
		)
		(fp_line
			(start 0.67945 -0.305054)
			(end 0.12065 -0.305054)
			(stroke
				(width 0.1)
				(type default)
			)
			(layer "B.Fab")
		)
		(fp_line
			(start 0.67945 0.3048)
			(end 0.67945 -0.305054)
			(stroke
				(width 0.1)
				(type default)
			)
			(layer "B.Fab")
		)
		(pad "1" smd circle
			(at 0.40005 0 180)
			(size 0 0)
			(layers "B.Cu" "B.Mask" "B.Paste")
			(net "BIC_SPI1DQ3")
		)
		(pad "2" smd circle
			(at -0.40005 0 180)
			(size 0 0)
			(layers "B.Cu" "B.Mask" "B.Paste")
			(net "P3V3_AUX")
		)
	)
	(footprint ""
		(layer "B.Cu")
		(at 305.471576 -114.592608)
		(property "Reference" "C929"
			(at 0 0 0)
			(layer "B.SilkS")
			(hide yes)
			(effects
				(font
					(size 1.27 1.27)
				)
				(justify mirror)
			)
		)
		(property "Value" ""
			(at 0 0 0)
			(layer "B.Fab")
			(effects
				(font
					(size 1.27 1.27)
				)
				(justify mirror)
			)
		)
		(duplicate_pad_numbers_are_jumpers no)
		(fp_line
			(start -0.7874 -0.4064)
			(end -0.7874 0.4064)
			(stroke
				(width 0.1524)
				(type default)
			)
			(layer "B.SilkS")
		)
		(fp_line
			(start -0.7874 0.4064)
			(end 0.7874 0.4064)
			(stroke
				(width 0.1524)
				(type default)
			)
			(layer "B.SilkS")
		)
		(fp_line
			(start 0.7874 -0.4064)
			(end -0.7874 -0.4064)
			(stroke
				(width 0.1524)
				(type default)
			)
			(layer "B.SilkS")
		)
		(fp_line
			(start 0.7874 0.4064)
			(end 0.7874 -0.4064)
			(stroke
				(width 0.1524)
				(type default)
			)
			(layer "B.SilkS")
		)
		(fp_line
			(start -0.67945 -0.3048)
			(end -0.67945 0.3048)
			(stroke
				(width 0.1)
				(type default)
			)
			(layer "B.Fab")
		)
		(fp_line
			(start -0.67945 0.3048)
			(end -0.120396 0.3048)
			(stroke
				(width 0.1)
				(type default)
			)
			(layer "B.Fab")
		)
		(fp_line
			(start -0.12065 -0.3048)
			(end -0.67945 -0.3048)
			(stroke
				(width 0.1)
				(type default)
			)
			(layer "B.Fab")
		)
		(fp_line
			(start -0.12065 -0.2794)
			(end -0.12065 -0.3048)
			(stroke
				(width 0.1)
				(type default)
			)
			(layer "B.Fab")
		)
		(fp_line
			(start -0.120396 0.2794)
			(end 0.12065 0.2794)
			(stroke
				(width 0.1)
				(type default)
			)
			(layer "B.Fab")
		)
		(fp_line
			(start -0.120396 0.3048)
			(end -0.120396 0.2794)
			(stroke
				(width 0.1)
				(type default)
			)
			(layer "B.Fab")
		)
		(fp_line
			(start 0.12065 -0.305054)
			(end 0.12065 -0.2794)
			(stroke
				(width 0.1)
				(type default)
			)
			(layer "B.Fab")
		)
		(fp_line
			(start 0.12065 -0.2794)
			(end -0.12065 -0.2794)
			(stroke
				(width 0.1)
				(type default)
			)
			(layer "B.Fab")
		)
		(fp_line
			(start 0.12065 0.2794)
			(end 0.12065 0.3048)
			(stroke
				(width 0.1)
				(type default)
			)
			(layer "B.Fab")
		)
		(fp_line
			(start 0.12065 0.3048)
			(end 0.67945 0.3048)
			(stroke
				(width 0.1)
				(type default)
			)
			(layer "B.Fab")
		)
		(fp_line
			(start 0.67945 -0.305054)
			(end 0.12065 -0.305054)
			(stroke
				(width 0.1)
				(type default)
			)
			(layer "B.Fab")
		)
		(fp_line
			(start 0.67945 0.3048)
			(end 0.67945 -0.305054)
			(stroke
				(width 0.1)
				(type default)
			)
			(layer "B.Fab")
		)
		(pad "1" smd circle
			(at 0.40005 0 180)
			(size 0 0)
			(layers "B.Cu" "B.Mask" "B.Paste")
			(net "P3V3_NIC5")
		)
		(pad "2" smd circle
			(at -0.40005 0 180)
			(size 0 0)
			(layers "B.Cu" "B.Mask" "B.Paste")
			(net "GND")
		)
	)
	(footprint ""
		(layer "B.Cu")
		(at 421.700198 -110.115096)
		(property "Reference" "C954"
			(at 0 0 0)
			(layer "B.SilkS")
			(hide yes)
			(effects
				(font
					(size 1.27 1.27)
				)
				(justify mirror)
			)
		)
		(property "Value" ""
			(at 0 0 0)
			(layer "B.Fab")
			(effects
				(font
					(size 1.27 1.27)
				)
				(justify mirror)
			)
		)
		(duplicate_pad_numbers_are_jumpers no)
		(fp_line
			(start -0.299974 -0.150114)
			(end -0.299974 0.150114)
			(stroke
				(width 0.1)
				(type default)
			)
			(layer "B.Fab")
		)
		(fp_line
			(start -0.299974 0.150114)
			(end 0.299974 0.150114)
			(stroke
				(width 0.1)
				(type default)
			)
			(layer "B.Fab")
		)
		(fp_line
			(start 0.299974 -0.150114)
			(end -0.299974 -0.150114)
			(stroke
				(width 0.1)
				(type default)
			)
			(layer "B.Fab")
		)
		(fp_line
			(start 0.299974 0.150114)
			(end 0.299974 -0.150114)
			(stroke
				(width 0.1)
				(type default)
			)
			(layer "B.Fab")
		)
		(pad "1" smd rect
			(at 0.2667 0 180)
			(size 0.3048 0.381)
			(layers "B.Cu" "B.Mask" "B.Paste")
			(net "P12V_NIC7")
		)
		(pad "2" smd rect
			(at -0.2667 0 180)
			(size 0.3048 0.381)
			(layers "B.Cu" "B.Mask" "B.Paste")
			(net "GND")
		)
	)
	(footprint ""
		(layer "B.Cu")
		(at 66.299842 -290.199826 90)
		(property "Reference" "C1172"
			(at 0 0 90)
			(layer "B.SilkS")
			(hide yes)
			(effects
				(font
					(size 1.27 1.27)
				)
				(justify mirror)
			)
		)
		(property "Value" ""
			(at 0 0 90)
			(layer "B.Fab")
			(effects
				(font
					(size 1.27 1.27)
				)
				(justify mirror)
			)
		)
		(duplicate_pad_numbers_are_jumpers no)
		(fp_line
			(start 0.299974 -0.150114)
			(end -0.299974 -0.150114)
			(stroke
				(width 0.1)
				(type default)
			)
			(layer "B.Fab")
		)
		(fp_line
			(start -0.299974 -0.150114)
			(end -0.299974 0.150114)
			(stroke
				(width 0.1)
				(type default)
			)
			(layer "B.Fab")
		)
		(fp_line
			(start 0.299974 0.150114)
			(end 0.299974 -0.150114)
			(stroke
				(width 0.1)
				(type default)
			)
			(layer "B.Fab")
		)
		(fp_line
			(start -0.299974 0.150114)
			(end 0.299974 0.150114)
			(stroke
				(width 0.1)
				(type default)
			)
			(layer "B.Fab")
		)
		(pad "1" smd rect
			(at 0.2667 0 270)
			(size 0.3048 0.381)
			(layers "B.Cu" "B.Mask" "B.Paste")
			(net "P0V8_SERDES_VDDA_PEX0")
		)
		(pad "2" smd rect
			(at -0.2667 0 270)
			(size 0.3048 0.381)
			(layers "B.Cu" "B.Mask" "B.Paste")
			(net "GND")
		)
	)
)
